# T6G (Grand Teton) — schematic netlist excerpt (pin names and nets, part order shuffled) for the footprints in the layout excerpt that follows; sources: Cadence DE-HDL packaged netlist, KiCad conversion of 04192023_DAF0TMB3IC0_F0TG_MB_C_brd_V02_OCP.brd

J24  SCONN288_DDR506112002KQ  IO  pkg DDR288S_1-1VXC  page 98
  VIN_BULK0  = P12V_MEM_CPU1
  RFU0  = NC
  VIN_MGMT  = P3V3_AUX
  HSCL  = I3C_SPD_DDRA_CPU1_SCL
  HSDA  = I3C_SPD_DDRA_CPU1_SDA
  VSS0  = GND
  DQ0_A  = M_A_CPU1_SA_DQ<0>
  VSS1  = GND
  DQ1_A  = M_A_CPU1_SA_DQ<1>
  VSS2  = GND
  DQS0_A_T  = M_A_CPU1_SA_DQS_DP<0>
  DQS0_A_C  = M_A_CPU1_SA_DQS_DN<0>
  VSS3  = GND
  DQ4_A  = M_A_CPU1_SA_DQ<4>
  VSS4  = GND
  DQ5_A  = M_A_CPU1_SA_DQ<5>
  VSS5  = GND
  DQ8_A  = M_A_CPU1_SA_DQ<8>
  VSS6  = GND
  DQ9_A  = M_A_CPU1_SA_DQ<9>
  VSS7  = GND
  DQS1_A_T  = M_A_CPU1_SA_DQS_DP<1>
  DQS1_A_C  = M_A_CPU1_SA_DQS_DN<1>
  VSS8  = GND
  DQ12_A  = M_A_CPU1_SA_DQ<12>
  VSS9  = GND
  DQ13_A  = M_A_CPU1_SA_DQ<13>
  VSS10  = GND
  DQ16_A  = M_A_CPU1_SA_DQ<16>
  VSS11  = GND
  DQ17_A  = M_A_CPU1_SA_DQ<17>
  VSS12  = GND
  DQS2_A_T  = M_A_CPU1_SA_DQS_DP<2>
  DQS2_A_C  = M_A_CPU1_SA_DQS_DN<2>
  VSS13  = GND
  DQ20_A  = M_A_CPU1_SA_DQ<20>
  VSS14  = GND
  DQ21_A  = M_A_CPU1_SA_DQ<21>
  VSS15  = GND
  DQ24_A  = M_A_CPU1_SA_DQ<24>
  VSS16  = GND
  DQ25_A  = M_A_CPU1_SA_DQ<25>
  VSS17  = GND
  DQS3_A_T  = M_A_CPU1_SA_DQS_DP<3>
  DQS3_A_C  = M_A_CPU1_SA_DQS_DN<3>
  VSS18  = GND
  DQ28_A  = M_A_CPU1_SA_DQ<28>
  VSS19  = GND
  DQ29_A  = M_A_CPU1_SA_DQ<29>
  VSS20  = GND
  CB0_A  = M_A_CPU1_SA_CB<0>
  VSS21  = GND
  CB1_A  = M_A_CPU1_SA_CB<1>
  VSS22  = GND
  DQS4_A_T  = M_A_CPU1_SA_DQS_DP<4>
  DQS4_A_C  = M_A_CPU1_SA_DQS_DN<4>
  VSS23  = GND
  CB4_A  = M_A_CPU1_SA_CB<4>
  VSS24  = GND
  CB5_A  = M_A_CPU1_SA_CB<5>
  VSS25  = GND
  ALERT_N  = M_A_CPU1_ALERT_N
  VSS26  = GND
  CS0_A_N  = M_A_CPU1_SA_CS_N<0>
  VSS27  = GND
  CA0_A  = M_A_CPU1_SA_CA<0>
  VSS28  = GND
  CA2_A  = M_A_CPU1_SA_CA<2>
  VSS29  = GND
  CA4_A  = M_A_CPU1_SA_CA<4>
  VSS30  = GND
  CA6_A  = M_A_CPU1_SA_CA<6>
  VSS31  = GND
  PAR_A  = M_A_CPU1_SA_PAR
  VSS32  = GND
  CA0_B  = M_A_CPU1_SB_CA<0>
  VSS33  = GND
  CA2_B  = M_A_CPU1_SB_CA<2>
  VSS34  = GND
  CA4_B  = M_A_CPU1_SB_CA<4>
  VSS35  = GND
  CA6_B  = M_A_CPU1_SB_CA<6>
  VSS36  = GND
  CS0_B_N  = M_A_CPU1_SB_CS_N<0>
  VSS37  = GND
  \lbd||rsp_a_n\  = M_A_CPU1_SA_RSP<0>
  \lbs||rsp_b_n\  = M_A_CPU1_SB_RSP<0>
  VSS38  = GND
  CB4_B  = M_A_CPU1_SB_CB<4>
  VSS39  = GND
  CB5_B  = M_A_CPU1_SB_CB<5>
  VSS40  = GND
  \dqs9_b_t||tdqs9_b_t||dbi4_b_n\  = M_A_CPU1_SB_DQS_DP<9>
  \dqs9_b_c||tdqs9_b_c\  = M_A_CPU1_SB_DQS_DN<9>
  VSS41  = GND
  CB0_B  = M_A_CPU1_SB_CB<0>
  VSS42  = GND
  CB1_B  = M_A_CPU1_SB_CB<1>
  VSS43  = GND
  DQ0_B  = M_A_CPU1_SB_DQ<0>
  VSS44  = GND
  DQ1_B  = M_A_CPU1_SB_DQ<1>
  VSS45  = GND
  DQS0_B_T  = M_A_CPU1_SB_DQS_DP<0>
  DQS0_B_C  = M_A_CPU1_SB_DQS_DN<0>
  VSS46  = GND
  DQ4_B  = M_A_CPU1_SB_DQ<4>
  VSS47  = GND
  DQ5_B  = M_A_CPU1_SB_DQ<5>
  VSS48  = GND
  DQ8_B  = M_A_CPU1_SB_DQ<8>
  VSS49  = GND
  DQ9_B  = M_A_CPU1_SB_DQ<9>
  VSS50  = GND
  DQS1_B_T  = M_A_CPU1_SB_DQS_DP<1>
  DQS1_B_C  = M_A_CPU1_SB_DQS_DN<1>
  VSS51  = GND
  DQ12_B  = M_A_CPU1_SB_DQ<12>
  VSS52  = GND
  DQ13_B  = M_A_CPU1_SB_DQ<13>
  VSS53  = GND
  DQ16_B  = M_A_CPU1_SB_DQ<16>
  VSS54  = GND
  DQ17_B  = M_A_CPU1_SB_DQ<17>
  VSS55  = GND
  DQS2_B_T  = M_A_CPU1_SB_DQS_DP<2>
  DQS2_B_C  = M_A_CPU1_SB_DQS_DN<2>
  VSS56  = GND
  DQ20_B  = M_A_CPU1_SB_DQ<20>
  VSS57  = GND
  DQ21_B  = M_A_CPU1_SB_DQ<21>
  VSS58  = GND
  DQ24_B  = M_A_CPU1_SB_DQ<24>
  VSS59  = GND
  DQ25_B  = M_A_CPU1_SB_DQ<25>
  VSS60  = GND
  DQS3_B_T  = M_A_CPU1_SB_DQS_DP<3>
  DQS3_B_C  = M_A_CPU1_SB_DQS_DN<3>
  VSS61  = GND
  DQ28_B  = M_A_CPU1_SB_DQ<28>
  VSS62  = GND
  DQ29_B  = M_A_CPU1_SB_DQ<29>
  VSS63  = GND
  RFU1  = NC
  VIN_BULK1  = P12V_MEM_CPU1
  VIN_BULK2  = P12V_MEM_CPU1
  \pwr_good||fail_n\  = PWRGD_CHA_CPU1_DIMM0
  HAS  = PD_CHA_CPU1_DIMM0_SAA
  RFU2  = NC
  RFU3  = NC
  VSS64  = GND
  DQ2_A  = M_A_CPU1_SA_DQ<2>
  VSS65  = GND
  DQ3_A  = M_A_CPU1_SA_DQ<3>
  VSS66  = GND
  \dqs5_a_c||tdqs5_a_c||dqs5_a_t||tdqs5_a_t\  = M_A_CPU1_SA_DQS_DN<5>
  \dqs5_a_t||tdqs5_a_t\  = M_A_CPU1_SA_DQS_DP<5>
  VSS67  = GND
  DQ6_A  = M_A_CPU1_SA_DQ<6>
  VSS68  = GND
  DQ7_A  = M_A_CPU1_SA_DQ<7>
  VSS69  = GND
  DQ10_A  = M_A_CPU1_SA_DQ<10>
  VSS70  = GND
  DQ11_A  = M_A_CPU1_SA_DQ<11>
  VSS71  = GND
  \dqs6_a_c||tdqs6_a_c||dqs6_a_t||tdqs6_a_t\  = M_A_CPU1_SA_DQS_DN<6>
  \dqs6_a_t||tdqs6_a_t\  = M_A_CPU1_SA_DQS_DP<6>
  VSS72  = GND
  DQ14_A  = M_A_CPU1_SA_DQ<14>
  VSS73  = GND
  DQ15_A  = M_A_CPU1_SA_DQ<15>
  VSS74  = GND
  DQ18_A  = M_A_CPU1_SA_DQ<18>
  VSS75  = GND
  DQ19_A  = M_A_CPU1_SA_DQ<19>
  VSS76  = GND
  \dqs7_a_c||tdqs7_a_c\  = M_A_CPU1_SA_DQS_DN<7>
  \dqs7_a_t||tdqs7_a_t\  = M_A_CPU1_SA_DQS_DP<7>
  VSS77  = GND
  DQ22_A  = M_A_CPU1_SA_DQ<22>
  VSS78  = GND
  DQ23_A  = M_A_CPU1_SA_DQ<23>
  VSS79  = GND
  DQ26_A  = M_A_CPU1_SA_DQ<26>
  VSS80  = GND
  DQ27_A  = M_A_CPU1_SA_DQ<27>
  VSS81  = GND
  \dqs8_a_c||tdqs8_a_c\  = M_A_CPU1_SA_DQS_DN<8>
  \dqs8_a_t||tdqs8_a_t\  = M_A_CPU1_SA_DQS_DP<8>
  VSS82  = GND
  DQ30_A  = M_A_CPU1_SA_DQ<30>
  VSS83  = GND
  DQ31_A  = M_A_CPU1_SA_DQ<31>
  VSS84  = GND
  CB2_A  = M_A_CPU1_SA_CB<2>
  VSS85  = GND
  CB3_A  = M_A_CPU1_SA_CB<3>
  VSS86  = GND
  \dqs9_a_c||tdqs9_a_c\  = M_A_CPU1_SA_DQS_DN<9>
  \dqs9_a_t||tdqs9_a_t\  = M_A_CPU1_SA_DQS_DP<9>
  VSS87  = GND
  CB6_A  = M_A_CPU1_SA_CB<6>
  VSS88  = GND
  CB7_A  = M_A_CPU1_SA_CB<7>
  VSS89  = GND
  RESET_N  = M_A_CPU1_RESET_N
  VSS90  = GND
  CS1_A_N  = M_A_CPU1_SA_CS_N<1>
  VSS91  = GND
  CA1_A  = M_A_CPU1_SA_CA<1>
  VSS92  = GND
  CA3_A  = M_A_CPU1_SA_CA<3>
  VSS93  = GND
  CA5_A  = M_A_CPU1_SA_CA<5>
  VSS94  = GND
  CK_T  = M_A_CPU1_CLK_DP<0>
  CK_C  = M_A_CPU1_CLK_DN<0>
  VSS95  = GND
  RFU4  = NC
  CA1_B  = M_A_CPU1_SB_CA<1>
  VSS96  = GND
  CA3_B  = M_A_CPU1_SB_CA<3>
  VSS97  = GND
  CA5_B  = M_A_CPU1_SB_CA<5>
  VSS98  = GND
  PAR_B  = M_A_CPU1_SB_PAR
  VSS99  = GND
  CS1_B_N  = M_A_CPU1_SB_CS_N<1>
  VSS100  = GND
  RFU5  = NC
  RFU6  = NC
  VSS101  = GND
  CB6_B  = M_A_CPU1_SB_CB<6>
  VSS102  = GND
  CB7_B  = M_A_CPU1_SB_CB<7>
  VSS103  = GND
  DQS4_B_C  = M_A_CPU1_SB_DQS_DN<4>
  DQS4_B_T  = M_A_CPU1_SB_DQS_DP<4>
  VSS104  = GND
  CB2_B  = M_A_CPU1_SB_CB<2>
  VSS105  = GND
  CB3_B  = M_A_CPU1_SB_CB<3>
  VSS106  = GND
  DQ2_B  = M_A_CPU1_SB_DQ<2>
  VSS107  = GND
  DQ3_B  = M_A_CPU1_SB_DQ<3>
  VSS108  = GND
  \dqs5_b_c||tdqs5_b_c\  = M_A_CPU1_SB_DQS_DN<5>
  \dqs5_b_t||tdqs5_b_t\  = M_A_CPU1_SB_DQS_DP<5>
  VSS109  = GND
  DQ6_B  = M_A_CPU1_SB_DQ<6>
  VSS110  = GND
  DQ7_B  = M_A_CPU1_SB_DQ<7>
  VSS111  = GND
  DQ10_B  = M_A_CPU1_SB_DQ<10>
  VSS112  = GND
  DQ11_B  = M_A_CPU1_SB_DQ<11>
  VSS113  = GND
  \dqs6_b_c||tdqs6_b_c\  = M_A_CPU1_SB_DQS_DN<6>
  \dqs6_b_t||tdqs6_b_t\  = M_A_CPU1_SB_DQS_DP<6>
  VSS114  = GND
  DQ14_B  = M_A_CPU1_SB_DQ<14>
  VSS115  = GND
  DQ15_B  = M_A_CPU1_SB_DQ<15>
  VSS116  = GND
  DQ18_B  = M_A_CPU1_SB_DQ<18>
  VSS117  = GND
  DQ19_B  = M_A_CPU1_SB_DQ<19>
  VSS118  = GND
  \dqs7_b_c||tdqs7_b_c\  = M_A_CPU1_SB_DQS_DN<7>
  \dqs7_b_t||tdqs7_b_t\  = M_A_CPU1_SB_DQS_DP<7>
  VSS119  = GND
  DQ22_B  = M_A_CPU1_SB_DQ<22>
  VSS120  = GND
  DQ23_B  = M_A_CPU1_SB_DQ<23>
  VSS121  = GND
  DQ26_B  = M_A_CPU1_SB_DQ<26>
  VSS122  = GND
  DQ27_B  = M_A_CPU1_SB_DQ<27>
  VSS123  = GND
  \dqs8_b_c||tdqs8_b_c\  = M_A_CPU1_SB_DQS_DN<8>
  \dqs8_b_t||tdqs8_b_t\  = M_A_CPU1_SB_DQS_DP<8>
  VSS124  = GND
  DQ30_B  = M_A_CPU1_SB_DQ<30>
  VSS125  = GND
  DQ31_B  = M_A_CPU1_SB_DQ<31>
  VSS126  = GND
  G1  = GND
  G2  = GND
  G3  = GND

(kicad_pcb
	(version 20260206)
	(generator "pcbnew")
	(generator_version "10.0")
	(general
		(thickness 1.6)
		(legacy_teardrops no)
	)
	(paper "A4")
	(title_block
		(title "04192023_DAF0TMB3IC0_F0TG_MB_C_brd_V02_OCP.brd")
		(comment 1 "Grand Teton / footprint 2100 of 8354 (J24), pads 1-46 of 291")
	)
	(layers
		(0 "F.Cu" signal "TOP")
		(4 "In1.Cu" signal "GND")
		(6 "In2.Cu" signal "IN1")
		(8 "In3.Cu" signal "GND1")
		(10 "In4.Cu" signal "IN2")
		(12 "In5.Cu" signal "GND2")
		(14 "In6.Cu" signal "IN3")
		(16 "In7.Cu" signal "GND3")
		(18 "In8.Cu" signal "VCC")
		(20 "In9.Cu" signal "VCC1")
		(22 "In10.Cu" signal "GND4")
		(24 "In11.Cu" signal "IN4")
		(26 "In12.Cu" signal "GND5")
		(28 "In13.Cu" signal "IN5")
		(30 "In14.Cu" signal "GND6")
		(32 "In15.Cu" signal "IN6")
		(34 "In16.Cu" signal "GND7")
		(2 "B.Cu" signal "BOTTOM")
		(9 "F.Adhes" user "F.Adhesive")
		(11 "B.Adhes" user "B.Adhesive")
		(13 "F.Paste" user "Package Geometry/Pastemask Top")
		(15 "B.Paste" user "Package Geometry/Pastemask Bottom")
		(5 "F.SilkS" user "Ref Des/Silkscreen Top")
		(7 "B.SilkS" user "Ref Des/Silkscreen Bottom")
		(1 "F.Mask" user "Board Geometry/Soldermask Top")
		(3 "B.Mask" user "Board Geometry/Soldermask Bottom")
		(17 "Dwgs.User" user "User.Drawings")
		(19 "Cmts.User" user "User.Comments")
		(21 "Eco1.User" user "User.Eco1")
		(23 "Eco2.User" user "User.Eco2")
		(25 "Edge.Cuts" user "Board Geometry/Outline")
		(27 "Margin" user)
		(31 "F.CrtYd" user "Package Geometry/Place Bound Top")
		(29 "B.CrtYd" user "Package Geometry/Place Bound Bottom")
		(35 "F.Fab" user "Ref Des/Assembly Top")
		(33 "B.Fab" user "Ref Des/Assembly Bottom")
	)
	(footprint ""
		(layer "F.Cu")
		(at 57.378092 -255.560322 180)
		(property "Reference" "J24"
			(at 1.914906 -84.58708 0)
			(unlocked yes)
			(layer "F.SilkS")
			(effects
				(font
					(size 0.7874 0.5842)
					(thickness 0.1524)
				)
			)
		)
		(property "Value" ""
			(at 0 0 180)
			(layer "F.Fab")
			(effects
				(font
					(size 1.27 1.27)
				)
			)
		)
		(duplicate_pad_numbers_are_jumpers no)
		(pad "1" smd rect
			(at -2.050034 -63.324994 90)
			(size 0.519938 1.4986)
			(layers "F.Cu" "F.Mask" "F.Paste")
			(net "P12V_MEM_CPU1")
		)
		(pad "2" smd rect
			(at -2.050034 -62.47511 90)
			(size 0.519938 1.4986)
			(layers "F.Cu" "F.Mask" "F.Paste")
			(net "Net_2256")
		)
		(pad "3" smd rect
			(at -2.050034 -61.624972 90)
			(size 0.519938 1.4986)
			(layers "F.Cu" "F.Mask" "F.Paste")
			(net "P3V3_AUX")
		)
		(pad "4" smd rect
			(at -2.050034 -60.775088 90)
			(size 0.519938 1.4986)
			(layers "F.Cu" "F.Mask" "F.Paste")
			(net "I3C_SPD_DDRA_CPU1_SCL")
		)
		(pad "5" smd rect
			(at -2.050034 -59.92495 90)
			(size 0.519938 1.4986)
			(layers "F.Cu" "F.Mask" "F.Paste")
			(net "I3C_SPD_DDRA_CPU1_SDA")
		)
		(pad "6" smd rect
			(at -2.050034 -59.075066 90)
			(size 0.519938 1.4986)
			(layers "F.Cu" "F.Mask" "F.Paste")
			(net "GND")
		)
		(pad "7" smd rect
			(at -2.050034 -58.224928 90)
			(size 0.519938 1.4986)
			(layers "F.Cu" "F.Mask" "F.Paste")
			(net "M_A_CPU1_SA_DQ<0>")
		)
		(pad "8" smd rect
			(at -2.050034 -57.375044 90)
			(size 0.519938 1.4986)
			(layers "F.Cu" "F.Mask" "F.Paste")
			(net "GND")
		)
		(pad "9" smd rect
			(at -2.050034 -56.524906 90)
			(size 0.519938 1.4986)
			(layers "F.Cu" "F.Mask" "F.Paste")
			(net "M_A_CPU1_SA_DQ<1>")
		)
		(pad "10" smd rect
			(at -2.050034 -55.675022 90)
			(size 0.519938 1.4986)
			(layers "F.Cu" "F.Mask" "F.Paste")
			(net "GND")
		)
		(pad "11" smd rect
			(at -2.050034 -54.824884 90)
			(size 0.519938 1.4986)
			(layers "F.Cu" "F.Mask" "F.Paste")
			(net "M_A_CPU1_SA_DQS_DP<0>")
		)
		(pad "12" smd rect
			(at -2.050034 -53.975 90)
			(size 0.519938 1.4986)
			(layers "F.Cu" "F.Mask" "F.Paste")
			(net "M_A_CPU1_SA_DQS_DN<0>")
		)
		(pad "13" smd rect
			(at -2.050034 -53.125116 90)
			(size 0.519938 1.4986)
			(layers "F.Cu" "F.Mask" "F.Paste")
			(net "GND")
		)
		(pad "14" smd rect
			(at -2.050034 -52.274978 90)
			(size 0.519938 1.4986)
			(layers "F.Cu" "F.Mask" "F.Paste")
			(net "M_A_CPU1_SA_DQ<4>")
		)
		(pad "15" smd rect
			(at -2.050034 -51.425094 90)
			(size 0.519938 1.4986)
			(layers "F.Cu" "F.Mask" "F.Paste")
			(net "GND")
		)
		(pad "16" smd rect
			(at -2.050034 -50.574956 90)
			(size 0.519938 1.4986)
			(layers "F.Cu" "F.Mask" "F.Paste")
			(net "M_A_CPU1_SA_DQ<5>")
		)
		(pad "17" smd rect
			(at -2.050034 -49.725072 90)
			(size 0.519938 1.4986)
			(layers "F.Cu" "F.Mask" "F.Paste")
			(net "GND")
		)
		(pad "18" smd rect
			(at -2.050034 -48.874934 90)
			(size 0.519938 1.4986)
			(layers "F.Cu" "F.Mask" "F.Paste")
			(net "M_A_CPU1_SA_DQ<8>")
		)
		(pad "19" smd rect
			(at -2.050034 -48.02505 90)
			(size 0.519938 1.4986)
			(layers "F.Cu" "F.Mask" "F.Paste")
			(net "GND")
		)
		(pad "20" smd rect
			(at -2.050034 -47.174912 90)
			(size 0.519938 1.4986)
			(layers "F.Cu" "F.Mask" "F.Paste")
			(net "M_A_CPU1_SA_DQ<9>")
		)
		(pad "21" smd rect
			(at -2.050034 -46.325028 90)
			(size 0.519938 1.4986)
			(layers "F.Cu" "F.Mask" "F.Paste")
			(net "GND")
		)
		(pad "22" smd rect
			(at -2.050034 -45.47489 90)
			(size 0.519938 1.4986)
			(layers "F.Cu" "F.Mask" "F.Paste")
			(net "M_A_CPU1_SA_DQS_DP<1>")
		)
		(pad "23" smd rect
			(at -2.050034 -44.625006 90)
			(size 0.519938 1.4986)
			(layers "F.Cu" "F.Mask" "F.Paste")
			(net "M_A_CPU1_SA_DQS_DN<1>")
		)
		(pad "24" smd rect
			(at -2.050034 -43.775122 90)
			(size 0.519938 1.4986)
			(layers "F.Cu" "F.Mask" "F.Paste")
			(net "GND")
		)
		(pad "25" smd rect
			(at -2.050034 -42.924984 90)
			(size 0.519938 1.4986)
			(layers "F.Cu" "F.Mask" "F.Paste")
			(net "M_A_CPU1_SA_DQ<12>")
		)
		(pad "26" smd rect
			(at -2.050034 -42.0751 90)
			(size 0.519938 1.4986)
			(layers "F.Cu" "F.Mask" "F.Paste")
			(net "GND")
		)
		(pad "27" smd rect
			(at -2.050034 -41.224962 90)
			(size 0.519938 1.4986)
			(layers "F.Cu" "F.Mask" "F.Paste")
			(net "M_A_CPU1_SA_DQ<13>")
		)
		(pad "28" smd rect
			(at -2.050034 -40.375078 90)
			(size 0.519938 1.4986)
			(layers "F.Cu" "F.Mask" "F.Paste")
			(net "GND")
		)
		(pad "29" smd rect
			(at -2.050034 -39.52494 90)
			(size 0.519938 1.4986)
			(layers "F.Cu" "F.Mask" "F.Paste")
			(net "M_A_CPU1_SA_DQ<16>")
		)
		(pad "30" smd rect
			(at -2.050034 -38.675056 90)
			(size 0.519938 1.4986)
			(layers "F.Cu" "F.Mask" "F.Paste")
			(net "GND")
		)
		(pad "31" smd rect
			(at -2.050034 -37.824918 90)
			(size 0.519938 1.4986)
			(layers "F.Cu" "F.Mask" "F.Paste")
			(net "M_A_CPU1_SA_DQ<17>")
		)
		(pad "32" smd rect
			(at -2.050034 -36.975034 90)
			(size 0.519938 1.4986)
			(layers "F.Cu" "F.Mask" "F.Paste")
			(net "GND")
		)
		(pad "33" smd rect
			(at -2.050034 -36.124896 90)
			(size 0.519938 1.4986)
			(layers "F.Cu" "F.Mask" "F.Paste")
			(net "M_A_CPU1_SA_DQS_DP<2>")
		)
		(pad "34" smd rect
			(at -2.050034 -35.275012 90)
			(size 0.519938 1.4986)
			(layers "F.Cu" "F.Mask" "F.Paste")
			(net "M_A_CPU1_SA_DQS_DN<2>")
		)
		(pad "35" smd rect
			(at -2.050034 -34.425128 90)
			(size 0.519938 1.4986)
			(layers "F.Cu" "F.Mask" "F.Paste")
			(net "GND")
		)
		(pad "36" smd rect
			(at -2.050034 -33.57499 90)
			(size 0.519938 1.4986)
			(layers "F.Cu" "F.Mask" "F.Paste")
			(net "M_A_CPU1_SA_DQ<20>")
		)
		(pad "37" smd rect
			(at -2.050034 -32.725106 90)
			(size 0.519938 1.4986)
			(layers "F.Cu" "F.Mask" "F.Paste")
			(net "GND")
		)
		(pad "38" smd rect
			(at -2.050034 -31.874968 90)
			(size 0.519938 1.4986)
			(layers "F.Cu" "F.Mask" "F.Paste")
			(net "M_A_CPU1_SA_DQ<21>")
		)
		(pad "39" smd rect
			(at -2.050034 -31.025084 90)
			(size 0.519938 1.4986)
			(layers "F.Cu" "F.Mask" "F.Paste")
			(net "GND")
		)
		(pad "40" smd rect
			(at -2.050034 -30.174946 90)
			(size 0.519938 1.4986)
			(layers "F.Cu" "F.Mask" "F.Paste")
			(net "M_A_CPU1_SA_DQ<24>")
		)
		(pad "41" smd rect
			(at -2.050034 -29.325062 90)
			(size 0.519938 1.4986)
			(layers "F.Cu" "F.Mask" "F.Paste")
			(net "GND")
		)
		(pad "42" smd rect
			(at -2.050034 -28.474924 90)
			(size 0.519938 1.4986)
			(layers "F.Cu" "F.Mask" "F.Paste")
			(net "M_A_CPU1_SA_DQ<25>")
		)
		(pad "43" smd rect
			(at -2.050034 -27.62504 90)
			(size 0.519938 1.4986)
			(layers "F.Cu" "F.Mask" "F.Paste")
			(net "GND")
		)
		(pad "44" smd rect
			(at -2.050034 -26.774902 90)
			(size 0.519938 1.4986)
			(layers "F.Cu" "F.Mask" "F.Paste")
			(net "M_A_CPU1_SA_DQS_DP<3>")
		)
		(pad "45" smd rect
			(at -2.050034 -25.925018 90)
			(size 0.519938 1.4986)
			(layers "F.Cu" "F.Mask" "F.Paste")
			(net "M_A_CPU1_SA_DQS_DN<3>")
		)
		(pad "46" smd rect
			(at -2.050034 -25.07488 90)
			(size 0.519938 1.4986)
			(layers "F.Cu" "F.Mask" "F.Paste")
			(net "GND")
		)
	)
)
